# T6G (Grand Teton) — schematic netlist excerpt (pin names and nets, part order shuffled) for the footprints in the layout excerpt that follows; sources: Cadence DE-HDL packaged netlist, KiCad conversion of 04192023_DAF0TMB3IC0_F0TG_MB_C_brd_V02_OCP.brd

R6865  Q_RES  33 5% CHIP  pkg 0402LF  page 151 : A = SMB_HOST_CLK_3V3AUX_SDA_R1 ; B = SMB_9ZXL045_P0_SDA
R3719  Q_RES  0 5% CHIP  pkg 0402LF  page 252 : A = SMB_LM75_2_3V3AUX_SCL_R ; B = SMB_LM75_2_3V3AUX_SCL

(kicad_pcb
	(version 20260206)
	(generator "pcbnew")
	(generator_version "10.0")
	(general
		(thickness 1.6)
		(legacy_teardrops no)
	)
	(paper "A4")
	(title_block
		(title "04192023_DAF0TMB3IC0_F0TG_MB_C_brd_V02_OCP.brd")
		(comment 1 "Grand Teton / footprints 896-897 of 8354")
	)
	(layers
		(0 "F.Cu" signal "TOP")
		(4 "In1.Cu" signal "GND")
		(6 "In2.Cu" signal "IN1")
		(8 "In3.Cu" signal "GND1")
		(10 "In4.Cu" signal "IN2")
		(12 "In5.Cu" signal "GND2")
		(14 "In6.Cu" signal "IN3")
		(16 "In7.Cu" signal "GND3")
		(18 "In8.Cu" signal "VCC")
		(20 "In9.Cu" signal "VCC1")
		(22 "In10.Cu" signal "GND4")
		(24 "In11.Cu" signal "IN4")
		(26 "In12.Cu" signal "GND5")
		(28 "In13.Cu" signal "IN5")
		(30 "In14.Cu" signal "GND6")
		(32 "In15.Cu" signal "IN6")
		(34 "In16.Cu" signal "GND7")
		(2 "B.Cu" signal "BOTTOM")
		(9 "F.Adhes" user "F.Adhesive")
		(11 "B.Adhes" user "B.Adhesive")
		(13 "F.Paste" user "Package Geometry/Pastemask Top")
		(15 "B.Paste" user "Package Geometry/Pastemask Bottom")
		(5 "F.SilkS" user "Ref Des/Silkscreen Top")
		(7 "B.SilkS" user "Ref Des/Silkscreen Bottom")
		(1 "F.Mask" user "Board Geometry/Soldermask Top")
		(3 "B.Mask" user "Board Geometry/Soldermask Bottom")
		(17 "Dwgs.User" user "User.Drawings")
		(19 "Cmts.User" user "User.Comments")
		(21 "Eco1.User" user "User.Eco1")
		(23 "Eco2.User" user "User.Eco2")
		(25 "Edge.Cuts" user "Board Geometry/Outline")
		(27 "Margin" user)
		(31 "F.CrtYd" user "Package Geometry/Place Bound Top")
		(29 "B.CrtYd" user "Package Geometry/Place Bound Bottom")
		(35 "F.Fab" user "Ref Des/Assembly Top")
		(33 "B.Fab" user "Ref Des/Assembly Bottom")
	)
	(footprint ""
		(layer "F.Cu")
		(at 279.659842 -415.1376)
		(property "Reference" "R6865"
			(at 0 0 0)
			(layer "F.SilkS")
			(hide yes)
			(effects
				(font
					(size 1.27 1.27)
				)
			)
		)
		(property "Value" ""
			(at 0 0 0)
			(layer "F.Fab")
			(effects
				(font
					(size 1.27 1.27)
				)
			)
		)
		(duplicate_pad_numbers_are_jumpers no)
		(fp_line
			(start -0.7874 -0.4064)
			(end 0.7874 -0.4064)
			(stroke
				(width 0.1524)
				(type default)
			)
			(layer "F.SilkS")
		)
		(fp_line
			(start -0.7874 0.4064)
			(end -0.7874 -0.4064)
			(stroke
				(width 0.1524)
				(type default)
			)
			(layer "F.SilkS")
		)
		(fp_line
			(start 0.7874 -0.4064)
			(end 0.7874 0.4064)
			(stroke
				(width 0.1524)
				(type default)
			)
			(layer "F.SilkS")
		)
		(fp_line
			(start 0.7874 0.4064)
			(end -0.7874 0.4064)
			(stroke
				(width 0.1524)
				(type default)
			)
			(layer "F.SilkS")
		)
		(fp_line
			(start -0.67945 -0.305054)
			(end -0.12065 -0.305054)
			(stroke
				(width 0.1)
				(type default)
			)
			(layer "F.Fab")
		)
		(fp_line
			(start -0.67945 0.3048)
			(end -0.67945 -0.305054)
			(stroke
				(width 0.1)
				(type default)
			)
			(layer "F.Fab")
		)
		(fp_line
			(start -0.12065 -0.305054)
			(end -0.12065 -0.2794)
			(stroke
				(width 0.1)
				(type default)
			)
			(layer "F.Fab")
		)
		(fp_line
			(start -0.12065 -0.2794)
			(end 0.12065 -0.2794)
			(stroke
				(width 0.1)
				(type default)
			)
			(layer "F.Fab")
		)
		(fp_line
			(start -0.12065 0.2794)
			(end -0.12065 0.3048)
			(stroke
				(width 0.1)
				(type default)
			)
			(layer "F.Fab")
		)
		(fp_line
			(start -0.12065 0.3048)
			(end -0.67945 0.3048)
			(stroke
				(width 0.1)
				(type default)
			)
			(layer "F.Fab")
		)
		(fp_line
			(start 0.120396 0.2794)
			(end -0.12065 0.2794)
			(stroke
				(width 0.1)
				(type default)
			)
			(layer "F.Fab")
		)
		(fp_line
			(start 0.120396 0.3048)
			(end 0.120396 0.2794)
			(stroke
				(width 0.1)
				(type default)
			)
			(layer "F.Fab")
		)
		(fp_line
			(start 0.12065 -0.3048)
			(end 0.67945 -0.3048)
			(stroke
				(width 0.1)
				(type default)
			)
			(layer "F.Fab")
		)
		(fp_line
			(start 0.12065 -0.2794)
			(end 0.12065 -0.3048)
			(stroke
				(width 0.1)
				(type default)
			)
			(layer "F.Fab")
		)
		(fp_line
			(start 0.67945 -0.3048)
			(end 0.67945 0.3048)
			(stroke
				(width 0.1)
				(type default)
			)
			(layer "F.Fab")
		)
		(fp_line
			(start 0.67945 0.3048)
			(end 0.120396 0.3048)
			(stroke
				(width 0.1)
				(type default)
			)
			(layer "F.Fab")
		)
		(pad "1" smd circle
			(at -0.40005 0)
			(size 0 0)
			(layers "F.Cu" "F.Mask" "F.Paste")
			(net "SMB_HOST_CLK_3V3AUX_SDA_R1")
		)
		(pad "2" smd circle
			(at 0.40005 0)
			(size 0 0)
			(layers "F.Cu" "F.Mask" "F.Paste")
			(net "SMB_9ZXL045_P0_SDA")
		)
	)
	(footprint ""
		(layer "F.Cu")
		(at 257.242056 -114.84737 180)
		(property "Reference" "R3719"
			(at 0 0 180)
			(layer "F.SilkS")
			(hide yes)
			(effects
				(font
					(size 1.27 1.27)
				)
			)
		)
		(property "Value" ""
			(at 0 0 180)
			(layer "F.Fab")
			(effects
				(font
					(size 1.27 1.27)
				)
			)
		)
		(duplicate_pad_numbers_are_jumpers no)
		(fp_line
			(start 0.7874 0.4064)
			(end -0.7874 0.4064)
			(stroke
				(width 0.1524)
				(type default)
			)
			(layer "F.SilkS")
		)
		(fp_line
			(start 0.7874 -0.4064)
			(end 0.7874 0.4064)
			(stroke
				(width 0.1524)
				(type default)
			)
			(layer "F.SilkS")
		)
		(fp_line
			(start -0.7874 0.4064)
			(end -0.7874 -0.4064)
			(stroke
				(width 0.1524)
				(type default)
			)
			(layer "F.SilkS")
		)
		(fp_line
			(start -0.7874 -0.4064)
			(end 0.7874 -0.4064)
			(stroke
				(width 0.1524)
				(type default)
			)
			(layer "F.SilkS")
		)
		(fp_line
			(start 0.67945 0.3048)
			(end 0.120396 0.3048)
			(stroke
				(width 0.1)
				(type default)
			)
			(layer "F.Fab")
		)
		(fp_line
			(start 0.67945 -0.3048)
			(end 0.67945 0.3048)
			(stroke
				(width 0.1)
				(type default)
			)
			(layer "F.Fab")
		)
		(fp_line
			(start 0.12065 -0.2794)
			(end 0.12065 -0.3048)
			(stroke
				(width 0.1)
				(type default)
			)
			(layer "F.Fab")
		)
		(fp_line
			(start 0.12065 -0.3048)
			(end 0.67945 -0.3048)
			(stroke
				(width 0.1)
				(type default)
			)
			(layer "F.Fab")
		)
		(fp_line
			(start 0.120396 0.3048)
			(end 0.120396 0.2794)
			(stroke
				(width 0.1)
				(type default)
			)
			(layer "F.Fab")
		)
		(fp_line
			(start 0.120396 0.2794)
			(end -0.12065 0.2794)
			(stroke
				(width 0.1)
				(type default)
			)
			(layer "F.Fab")
		)
		(fp_line
			(start -0.12065 0.3048)
			(end -0.67945 0.3048)
			(stroke
				(width 0.1)
				(type default)
			)
			(layer "F.Fab")
		)
		(fp_line
			(start -0.12065 0.2794)
			(end -0.12065 0.3048)
			(stroke
				(width 0.1)
				(type default)
			)
			(layer "F.Fab")
		)
		(fp_line
			(start -0.12065 -0.2794)
			(end 0.12065 -0.2794)
			(stroke
				(width 0.1)
				(type default)
			)
			(layer "F.Fab")
		)
		(fp_line
			(start -0.12065 -0.305054)
			(end -0.12065 -0.2794)
			(stroke
				(width 0.1)
				(type default)
			)
			(layer "F.Fab")
		)
		(fp_line
			(start -0.67945 0.3048)
			(end -0.67945 -0.305054)
			(stroke
				(width 0.1)
				(type default)
			)
			(layer "F.Fab")
		)
		(fp_line
			(start -0.67945 -0.305054)
			(end -0.12065 -0.305054)
			(stroke
				(width 0.1)
				(type default)
			)
			(layer "F.Fab")
		)
		(pad "1" smd circle
			(at -0.40005 0 180)
			(size 0 0)
			(layers "F.Cu" "F.Mask" "F.Paste")
			(net "SMB_LM75_2_3V3AUX_SCL_R")
		)
		(pad "2" smd circle
			(at 0.40005 0 180)
			(size 0 0)
			(layers "F.Cu" "F.Mask" "F.Paste")
			(net "SMB_LM75_2_3V3AUX_SCL")
		)
	)
)
